# S9S_MB_2U (Grand Teton) — schematic netlist excerpt (pin names and nets, part order shuffled) for the footprints in the layout excerpt that follows; sources: Cadence DE-HDL packaged netlist, KiCad conversion of 03242023_DA0F0TMBIJ0_F0T_Motherboard_J_brd_V01_OCP.brd

C686  Q_CAP_DIFFBUS  DIFF BUS_0.22UF 6.3V 20% X6S  pkg C0201  page 177 : \1\ = P5E_CPU1_PE4_TX_C_DN<11> ; \2\ = P5E_CPU1_PE4_TX_DN<11>
R2585  Q_RES  31.6K 1% CHIP  pkg 0402LF  page 301 : A = HSC_EN ; B = GND

Q54  MOSFET_NCH_GDS_ESD_PROTECTED  2N7002K IC  pkg SOT23_GDSXC  page 247
  D  = P12V_AUX_BLEEDING
  G  = FM_P12V_HSC_EN_R_N
  S  = GND

(kicad_pcb
	(version 20260206)
	(generator "pcbnew")
	(generator_version "10.0")
	(general
		(thickness 1.6)
		(legacy_teardrops no)
	)
	(paper "A4")
	(title_block
		(title "03242023_DA0F0TMBIJ0_F0T_Motherboard_J_brd_V01_OCP.brd")
		(comment 1 "Grand Teton / footprints 756-758 of 6105")
	)
	(layers
		(0 "F.Cu" signal "TOP")
		(4 "In1.Cu" signal "GND")
		(6 "In2.Cu" signal "IN1")
		(8 "In3.Cu" signal "GND1")
		(10 "In4.Cu" signal "IN2")
		(12 "In5.Cu" signal "GND2")
		(14 "In6.Cu" signal "IN3")
		(16 "In7.Cu" signal "GND3")
		(18 "In8.Cu" signal "VCC")
		(20 "In9.Cu" signal "VCC1")
		(22 "In10.Cu" signal "GND4")
		(24 "In11.Cu" signal "IN4")
		(26 "In12.Cu" signal "GND5")
		(28 "In13.Cu" signal "IN5")
		(30 "In14.Cu" signal "GND6")
		(32 "In15.Cu" signal "IN6")
		(34 "In16.Cu" signal "GND7")
		(2 "B.Cu" signal "BOTTOM")
		(9 "F.Adhes" user "F.Adhesive")
		(11 "B.Adhes" user "B.Adhesive")
		(13 "F.Paste" user "Package Geometry/Pastemask Top")
		(15 "B.Paste" user "Package Geometry/Pastemask Bottom")
		(5 "F.SilkS" user "Ref Des/Silkscreen Top")
		(7 "B.SilkS" user "Ref Des/Silkscreen Bottom")
		(1 "F.Mask" user "Board Geometry/Soldermask Top")
		(3 "B.Mask" user "Board Geometry/Soldermask Bottom")
		(17 "Dwgs.User" user "User.Drawings")
		(19 "Cmts.User" user "User.Comments")
		(21 "Eco1.User" user "User.Eco1")
		(23 "Eco2.User" user "User.Eco2")
		(25 "Edge.Cuts" user "Board Geometry/Outline")
		(27 "Margin" user)
		(31 "F.CrtYd" user "Package Geometry/Place Bound Top")
		(29 "B.CrtYd" user "Package Geometry/Place Bound Bottom")
		(35 "F.Fab" user "Ref Des/Assembly Top")
		(33 "B.Fab" user "Ref Des/Assembly Bottom")
	)
	(footprint ""
		(layer "F.Cu")
		(at 202.59294 -132.050028)
		(property "Reference" "Q54"
			(at -1.651 -2.25933 0)
			(unlocked yes)
			(layer "F.SilkS")
			(effects
				(font
					(size 0.7874 0.5842)
					(thickness 0.1524)
				)
				(justify left)
			)
		)
		(property "Value" ""
			(at 0 0 0)
			(layer "F.Fab")
			(effects
				(font
					(size 1.27 1.27)
				)
			)
		)
		(duplicate_pad_numbers_are_jumpers no)
		(fp_line
			(start -1.603248 -1.500124)
			(end 1.603248 -1.500124)
			(stroke
				(width 0.1524)
				(type default)
			)
			(layer "F.SilkS")
		)
		(fp_line
			(start -1.603248 1.500124)
			(end -1.603248 -1.500124)
			(stroke
				(width 0.1524)
				(type default)
			)
			(layer "F.SilkS")
		)
		(fp_line
			(start 1.603248 -1.500124)
			(end 1.603248 1.500124)
			(stroke
				(width 0.1524)
				(type default)
			)
			(layer "F.SilkS")
		)
		(fp_line
			(start 1.603248 1.500124)
			(end -1.603248 1.500124)
			(stroke
				(width 0.1524)
				(type default)
			)
			(layer "F.SilkS")
		)
		(fp_line
			(start -1.249934 -1.169924)
			(end -1.249934 -0.729996)
			(stroke
				(width 0.1)
				(type default)
			)
			(layer "F.Fab")
		)
		(fp_line
			(start -1.249934 -0.729996)
			(end -0.6985 -0.729996)
			(stroke
				(width 0.1)
				(type default)
			)
			(layer "F.Fab")
		)
		(fp_line
			(start -1.249934 0.729996)
			(end -1.249934 1.169924)
			(stroke
				(width 0.1)
				(type default)
			)
			(layer "F.Fab")
		)
		(fp_line
			(start -1.249934 1.169924)
			(end -0.700024 1.169924)
			(stroke
				(width 0.1)
				(type default)
			)
			(layer "F.Fab")
		)
		(fp_line
			(start -0.700024 -1.500124)
			(end -0.700024 -1.169924)
			(stroke
				(width 0.1)
				(type default)
			)
			(layer "F.Fab")
		)
		(fp_line
			(start -0.700024 -1.169924)
			(end -1.249934 -1.169924)
			(stroke
				(width 0.1)
				(type default)
			)
			(layer "F.Fab")
		)
		(fp_line
			(start -0.700024 1.169924)
			(end -0.700024 1.500124)
			(stroke
				(width 0.1)
				(type default)
			)
			(layer "F.Fab")
		)
		(fp_line
			(start -0.700024 1.500124)
			(end 0.700024 1.500124)
			(stroke
				(width 0.1)
				(type default)
			)
			(layer "F.Fab")
		)
		(fp_line
			(start -0.6985 -0.729996)
			(end -0.6985 0.729996)
			(stroke
				(width 0.1)
				(type default)
			)
			(layer "F.Fab")
		)
		(fp_line
			(start -0.6985 0.729996)
			(end -1.249934 0.729996)
			(stroke
				(width 0.1)
				(type default)
			)
			(layer "F.Fab")
		)
		(fp_line
			(start 0.700024 -1.500124)
			(end -0.700024 -1.500124)
			(stroke
				(width 0.1)
				(type default)
			)
			(layer "F.Fab")
		)
		(fp_line
			(start 0.700024 -0.219964)
			(end 0.700024 -1.500124)
			(stroke
				(width 0.1)
				(type default)
			)
			(layer "F.Fab")
		)
		(fp_line
			(start 0.700024 0.219964)
			(end 1.249934 0.219964)
			(stroke
				(width 0.1)
				(type default)
			)
			(layer "F.Fab")
		)
		(fp_line
			(start 0.700024 1.500124)
			(end 0.700024 0.219964)
			(stroke
				(width 0.1)
				(type default)
			)
			(layer "F.Fab")
		)
		(fp_line
			(start 1.249934 -0.219964)
			(end 0.700024 -0.219964)
			(stroke
				(width 0.1)
				(type default)
			)
			(layer "F.Fab")
		)
		(fp_line
			(start 1.249934 0.219964)
			(end 1.249934 -0.219964)
			(stroke
				(width 0.1)
				(type default)
			)
			(layer "F.Fab")
		)
		(fp_rect
			(start -0.700024 1.500124)
			(end 0.700024 -1.500124)
			(stroke
				(width 0)
				(type default)
			)
			(fill no)
			(layer "F.Fab")
		)
		(pad "D" smd rect
			(at 0.999998 0 270)
			(size 0.8128 0.9144)
			(layers "F.Cu" "F.Mask" "F.Paste")
			(net "P12V_AUX_BLEEDING")
		)
		(pad "G" smd rect
			(at -0.999998 -0.94996 270)
			(size 0.8128 0.9144)
			(layers "F.Cu" "F.Mask" "F.Paste")
			(net "FM_P12V_HSC_EN_R_N")
		)
		(pad "S" smd rect
			(at -0.999998 0.94996 270)
			(size 0.8128 0.9144)
			(layers "F.Cu" "F.Mask" "F.Paste")
			(net "GND")
		)
	)
	(footprint ""
		(layer "F.Cu")
		(at 188.839348 -423.86123 -90)
		(property "Reference" "R2585"
			(at 0 0 270)
			(layer "F.SilkS")
			(hide yes)
			(effects
				(font
					(size 1.27 1.27)
				)
			)
		)
		(property "Value" ""
			(at 0 0 270)
			(layer "F.Fab")
			(effects
				(font
					(size 1.27 1.27)
				)
			)
		)
		(duplicate_pad_numbers_are_jumpers no)
		(fp_line
			(start -0.7874 0.4064)
			(end -0.7874 -0.4064)
			(stroke
				(width 0.1524)
				(type default)
			)
			(layer "F.SilkS")
		)
		(fp_line
			(start 0.7874 0.4064)
			(end -0.7874 0.4064)
			(stroke
				(width 0.1524)
				(type default)
			)
			(layer "F.SilkS")
		)
		(fp_line
			(start -0.7874 -0.4064)
			(end 0.7874 -0.4064)
			(stroke
				(width 0.1524)
				(type default)
			)
			(layer "F.SilkS")
		)
		(fp_line
			(start 0.7874 -0.4064)
			(end 0.7874 0.4064)
			(stroke
				(width 0.1524)
				(type default)
			)
			(layer "F.SilkS")
		)
		(fp_line
			(start -0.67945 0.3048)
			(end -0.67945 -0.305054)
			(stroke
				(width 0.1)
				(type default)
			)
			(layer "F.Fab")
		)
		(fp_line
			(start -0.12065 0.3048)
			(end -0.67945 0.3048)
			(stroke
				(width 0.1)
				(type default)
			)
			(layer "F.Fab")
		)
		(fp_line
			(start 0.120396 0.3048)
			(end 0.120396 0.2794)
			(stroke
				(width 0.1)
				(type default)
			)
			(layer "F.Fab")
		)
		(fp_line
			(start 0.67945 0.3048)
			(end 0.120396 0.3048)
			(stroke
				(width 0.1)
				(type default)
			)
			(layer "F.Fab")
		)
		(fp_line
			(start -0.12065 0.2794)
			(end -0.12065 0.3048)
			(stroke
				(width 0.1)
				(type default)
			)
			(layer "F.Fab")
		)
		(fp_line
			(start 0.120396 0.2794)
			(end -0.12065 0.2794)
			(stroke
				(width 0.1)
				(type default)
			)
			(layer "F.Fab")
		)
		(fp_line
			(start -0.12065 -0.2794)
			(end 0.12065 -0.2794)
			(stroke
				(width 0.1)
				(type default)
			)
			(layer "F.Fab")
		)
		(fp_line
			(start 0.12065 -0.2794)
			(end 0.12065 -0.3048)
			(stroke
				(width 0.1)
				(type default)
			)
			(layer "F.Fab")
		)
		(fp_line
			(start 0.12065 -0.3048)
			(end 0.67945 -0.3048)
			(stroke
				(width 0.1)
				(type default)
			)
			(layer "F.Fab")
		)
		(fp_line
			(start 0.67945 -0.3048)
			(end 0.67945 0.3048)
			(stroke
				(width 0.1)
				(type default)
			)
			(layer "F.Fab")
		)
		(fp_line
			(start -0.67945 -0.305054)
			(end -0.12065 -0.305054)
			(stroke
				(width 0.1)
				(type default)
			)
			(layer "F.Fab")
		)
		(fp_line
			(start -0.12065 -0.305054)
			(end -0.12065 -0.2794)
			(stroke
				(width 0.1)
				(type default)
			)
			(layer "F.Fab")
		)
		(pad "1" smd circle
			(at -0.40005 0 270)
			(size 0 0)
			(layers "F.Cu" "F.Mask" "F.Paste")
			(net "HSC_EN")
		)
		(pad "2" smd circle
			(at 0.40005 0 270)
			(size 0 0)
			(layers "F.Cu" "F.Mask" "F.Paste")
			(net "GND")
		)
	)
	(footprint ""
		(layer "F.Cu")
		(at 83.910678 -408.517344 -90)
		(property "Reference" "C686"
			(at 0 0 270)
			(layer "F.SilkS")
			(hide yes)
			(effects
				(font
					(size 1.27 1.27)
				)
			)
		)
		(property "Value" ""
			(at 0 0 270)
			(layer "F.Fab")
			(effects
				(font
					(size 1.27 1.27)
				)
			)
		)
		(duplicate_pad_numbers_are_jumpers no)
		(fp_line
			(start -0.299974 0.150114)
			(end -0.299974 -0.150114)
			(stroke
				(width 0.1)
				(type default)
			)
			(layer "F.Fab")
		)
		(fp_line
			(start 0.299974 0.150114)
			(end -0.299974 0.150114)
			(stroke
				(width 0.1)
				(type default)
			)
			(layer "F.Fab")
		)
		(fp_line
			(start -0.299974 -0.150114)
			(end 0.299974 -0.150114)
			(stroke
				(width 0.1)
				(type default)
			)
			(layer "F.Fab")
		)
		(fp_line
			(start 0.299974 -0.150114)
			(end 0.299974 0.150114)
			(stroke
				(width 0.1)
				(type default)
			)
			(layer "F.Fab")
		)
		(pad "1" smd rect
			(at -0.2667 0 270)
			(size 0.3048 0.381)
			(layers "F.Cu" "F.Mask" "F.Paste")
			(net "P5E_CPU1_PE4_TX_C_DN<11>")
		)
		(pad "2" smd rect
			(at 0.2667 0 270)
			(size 0.3048 0.381)
			(layers "F.Cu" "F.Mask" "F.Paste")
			(net "P5E_CPU1_PE4_TX_DN<11>")
		)
	)
)
